(kicad_pcb
	(version 20260206)
	(generator "pcbnew")
	(generator_version "10.0")
	(general
		(thickness 1.6)
		(legacy_teardrops no)
	)
	(paper "A4")
	(title_block
		(title "baseboard — 13948-1b.1110WZS1818.brd")
		(comment 1 "Honey Badger (Wiwynn) / footprints 2055-2062 of 2523")
	)
	(layers
		(0 "F.Cu" signal "TOP")
		(4 "In1.Cu" signal "L2GND")
		(6 "In2.Cu" signal "L3")
		(8 "In3.Cu" signal "L4VCC")
		(10 "In4.Cu" signal "L5VCC")
		(12 "In5.Cu" signal "L6")
		(14 "In6.Cu" signal "L7GND")
		(2 "B.Cu" signal "BOTTOM")
		(9 "F.Adhes" user "F.Adhesive")
		(11 "B.Adhes" user "B.Adhesive")
		(13 "F.Paste" user "Package Geometry/Pastemask Top")
		(15 "B.Paste" user "Package Geometry/Pastemask Bottom")
		(5 "F.SilkS" user "Ref Des/Silkscreen Top")
		(7 "B.SilkS" user "Ref Des/Silkscreen Bottom")
		(1 "F.Mask" user "Board Geometry/Soldermask Top")
		(3 "B.Mask" user "Board Geometry/Soldermask Bottom")
		(17 "Dwgs.User" user "User.Drawings")
		(19 "Cmts.User" user "User.Comments")
		(21 "Eco1.User" user "User.Eco1")
		(23 "Eco2.User" user "User.Eco2")
		(25 "Edge.Cuts" user "Board Geometry/Outline")
		(27 "Margin" user)
		(31 "F.CrtYd" user "Package Geometry/Place Bound Top")
		(29 "B.CrtYd" user "Package Geometry/Place Bound Bottom")
		(35 "F.Fab" user "Ref Des/Assembly Top")
		(33 "B.Fab" user "Ref Des/Assembly Bottom")
	)
	(footprint ""
		(layer "B.Cu")
		(at 304.89398 -179.3875 180)
		(property "Reference" "C193"
			(at 0 0 0)
			(layer "B.SilkS")
			(hide yes)
			(effects
				(font
					(size 1.27 1.27)
				)
				(justify mirror)
			)
		)
		(property "Value" "SC100P50V2JN-3GP"
			(at -1.1811 -2.7051 180)
			(unlocked yes)
			(layer "B.Fab")
			(hide yes)
			(effects
				(font
					(size 1.016 1.016)
					(thickness 0.1524)
				)
				(justify mirror)
			)
		)
		(property "Device Type" "C402H22"
			(at -1.1811 -4.2291 180)
			(unlocked yes)
			(layer "B.Fab")
			(hide yes)
			(effects
				(font
					(size 1.016 1.016)
					(thickness 0.1524)
				)
				(justify mirror)
			)
		)
		(duplicate_pad_numbers_are_jumpers no)
		(fp_rect
			(start 0.4318 0.9525)
			(end -0.4318 -0.9525)
			(stroke
				(width 0)
				(type default)
			)
			(fill no)
			(layer "B.CrtYd")
		)
		(fp_rect
			(start 0.4318 0.9525)
			(end -0.4318 -0.9525)
			(stroke
				(width 0)
				(type default)
			)
			(fill no)
			(layer "B.Fab")
		)
		(pad "1" smd custom
			(at 0 -0.4445)
			(size 0.1524 0.1524)
			(layers "B.Cu" "B.Mask" "B.Paste")
			(net "ADCAV33")
			(options
				(clearance outline)
				(anchor circle)
			)
			(primitives
				(gr_poly
					(pts
						(arc
							(start 0.3048 0.2032)
							(mid 0.275042 0.275042)
							(end 0.2032 0.3048)
						)
						(arc
							(start -0.2032 0.3048)
							(mid -0.275042 0.275042)
							(end -0.3048 0.2032)
						)
						(arc
							(start -0.3048 -0.2032)
							(mid -0.275042 -0.275042)
							(end -0.2032 -0.3048)
						)
						(arc
							(start 0.2032 -0.3048)
							(mid 0.275042 -0.275042)
							(end 0.3048 -0.2032)
						)
					)
					(width 0)
					(fill yes)
				)
			)
		)
		(pad "2" smd custom
			(at 0 0.4445)
			(size 0.1524 0.1524)
			(layers "B.Cu" "B.Mask" "B.Paste")
			(net "GND")
			(options
				(clearance outline)
				(anchor circle)
			)
			(primitives
				(gr_poly
					(pts
						(arc
							(start 0.3048 0.2032)
							(mid 0.275042 0.275042)
							(end 0.2032 0.3048)
						)
						(arc
							(start -0.2032 0.3048)
							(mid -0.275042 0.275042)
							(end -0.3048 0.2032)
						)
						(arc
							(start -0.3048 -0.2032)
							(mid -0.275042 -0.275042)
							(end -0.2032 -0.3048)
						)
						(arc
							(start 0.2032 -0.3048)
							(mid 0.275042 -0.275042)
							(end 0.3048 -0.2032)
						)
					)
					(width 0)
					(fill yes)
				)
			)
		)
	)
	(footprint ""
		(layer "B.Cu")
		(at 121.67997 -89.916 180)
		(property "Reference" "SC1192"
			(at 0 0 0)
			(layer "B.SilkS")
			(hide yes)
			(effects
				(font
					(size 1.27 1.27)
				)
				(justify mirror)
			)
		)
		(property "Value" "SCD1U6D3V1KX-GP"
			(at 2.8321 -1.7399 180)
			(unlocked yes)
			(layer "B.Fab")
			(hide yes)
			(effects
				(font
					(size 1.016 1.016)
					(thickness 0.1524)
				)
				(justify mirror)
			)
		)
		(property "Device Type" "C0201H13"
			(at 2.8321 -3.2639 180)
			(unlocked yes)
			(layer "B.Fab")
			(hide yes)
			(effects
				(font
					(size 1.016 1.016)
					(thickness 0.1524)
				)
				(justify mirror)
			)
		)
		(duplicate_pad_numbers_are_jumpers no)
		(fp_rect
			(start 0.2794 0.6477)
			(end -0.2794 -0.6477)
			(stroke
				(width 0)
				(type default)
			)
			(fill no)
			(layer "B.CrtYd")
		)
		(fp_rect
			(start 0.2794 0.6477)
			(end -0.2794 -0.6477)
			(stroke
				(width 0)
				(type default)
			)
			(fill no)
			(layer "B.Fab")
		)
		(pad "1" smd custom
			(at 0 -0.2794)
			(size 0.0762 0.0762)
			(layers "B.Cu" "B.Mask" "B.Paste")
			(net "GB_VDDA")
			(options
				(clearance outline)
				(anchor circle)
			)
			(primitives
				(gr_poly
					(pts
						(arc
							(start 0.1524 0.127)
							(mid 0.137521 0.162921)
							(end 0.1016 0.1778)
						)
						(arc
							(start -0.1016 0.1778)
							(mid -0.137521 0.162921)
							(end -0.1524 0.127)
						)
						(arc
							(start -0.1524 -0.127)
							(mid -0.137521 -0.162921)
							(end -0.1016 -0.1778)
						)
						(arc
							(start 0.1016 -0.1778)
							(mid 0.137521 -0.162921)
							(end 0.1524 -0.127)
						)
					)
					(width 0)
					(fill yes)
				)
			)
		)
		(pad "2" smd custom
			(at 0 0.2794)
			(size 0.0762 0.0762)
			(layers "B.Cu" "B.Mask" "B.Paste")
			(net "GND")
			(options
				(clearance outline)
				(anchor circle)
			)
			(primitives
				(gr_poly
					(pts
						(arc
							(start 0.1524 0.127)
							(mid 0.137521 0.162921)
							(end 0.1016 0.1778)
						)
						(arc
							(start -0.1016 0.1778)
							(mid -0.137521 0.162921)
							(end -0.1524 0.127)
						)
						(arc
							(start -0.1524 -0.127)
							(mid -0.137521 -0.162921)
							(end -0.1016 -0.1778)
						)
						(arc
							(start 0.1016 -0.1778)
							(mid 0.137521 -0.162921)
							(end 0.1524 -0.127)
						)
					)
					(width 0)
					(fill yes)
				)
			)
		)
	)
	(footprint ""
		(layer "B.Cu")
		(at 293.878 -172.466 180)
		(property "Reference" "C217"
			(at 0 0 0)
			(layer "B.SilkS")
			(hide yes)
			(effects
				(font
					(size 1.27 1.27)
				)
				(justify mirror)
			)
		)
		(property "Value" "SC1U10V2KX-1GP"
			(at -1.1811 -2.7051 180)
			(unlocked yes)
			(layer "B.Fab")
			(hide yes)
			(effects
				(font
					(size 1.016 1.016)
					(thickness 0.1524)
				)
				(justify mirror)
			)
		)
		(property "Device Type" "C402H22"
			(at -1.1811 -4.2291 180)
			(unlocked yes)
			(layer "B.Fab")
			(hide yes)
			(effects
				(font
					(size 1.016 1.016)
					(thickness 0.1524)
				)
				(justify mirror)
			)
		)
		(duplicate_pad_numbers_are_jumpers no)
		(fp_rect
			(start 0.4318 0.9525)
			(end -0.4318 -0.9525)
			(stroke
				(width 0)
				(type default)
			)
			(fill no)
			(layer "B.CrtYd")
		)
		(fp_rect
			(start 0.4318 0.9525)
			(end -0.4318 -0.9525)
			(stroke
				(width 0)
				(type default)
			)
			(fill no)
			(layer "B.Fab")
		)
		(pad "1" smd custom
			(at 0 -0.4445)
			(size 0.1524 0.1524)
			(layers "B.Cu" "B.Mask" "B.Paste")
			(net "P3V3_STBY")
			(options
				(clearance outline)
				(anchor circle)
			)
			(primitives
				(gr_poly
					(pts
						(arc
							(start 0.3048 0.2032)
							(mid 0.275042 0.275042)
							(end 0.2032 0.3048)
						)
						(arc
							(start -0.2032 0.3048)
							(mid -0.275042 0.275042)
							(end -0.3048 0.2032)
						)
						(arc
							(start -0.3048 -0.2032)
							(mid -0.275042 -0.275042)
							(end -0.2032 -0.3048)
						)
						(arc
							(start 0.2032 -0.3048)
							(mid 0.275042 -0.275042)
							(end 0.3048 -0.2032)
						)
					)
					(width 0)
					(fill yes)
				)
			)
		)
		(pad "2" smd custom
			(at 0 0.4445)
			(size 0.1524 0.1524)
			(layers "B.Cu" "B.Mask" "B.Paste")
			(net "GND")
			(options
				(clearance outline)
				(anchor circle)
			)
			(primitives
				(gr_poly
					(pts
						(arc
							(start 0.3048 0.2032)
							(mid 0.275042 0.275042)
							(end 0.2032 0.3048)
						)
						(arc
							(start -0.2032 0.3048)
							(mid -0.275042 0.275042)
							(end -0.3048 0.2032)
						)
						(arc
							(start -0.3048 -0.2032)
							(mid -0.275042 -0.275042)
							(end -0.2032 -0.3048)
						)
						(arc
							(start 0.2032 -0.3048)
							(mid 0.275042 -0.275042)
							(end 0.3048 -0.2032)
						)
					)
					(width 0)
					(fill yes)
				)
			)
		)
	)
	(footprint ""
		(layer "B.Cu")
		(at 119.996966 -37.846 -90)
		(property "Reference" "SR620"
			(at 0 0 90)
			(layer "B.SilkS")
			(hide yes)
			(effects
				(font
					(size 1.27 1.27)
				)
				(justify mirror)
			)
		)
		(property "Value" "2K2R2F-GP"
			(at -0.064008 -3.993896 270)
			(unlocked yes)
			(layer "B.Fab")
			(hide yes)
			(effects
				(font
					(size 1.016 1.016)
					(thickness 0.1524)
				)
				(justify mirror)
			)
		)
		(property "Device Type" "R402H16"
			(at -0.064008 -5.517896 270)
			(unlocked yes)
			(layer "B.Fab")
			(hide yes)
			(effects
				(font
					(size 1.016 1.016)
					(thickness 0.1524)
				)
				(justify mirror)
			)
		)
		(duplicate_pad_numbers_are_jumpers no)
		(fp_line
			(start -0.508 -0.9398)
			(end 0.508 -0.9398)
			(stroke
				(width 0.1524)
				(type default)
			)
			(layer "B.SilkS")
		)
		(fp_line
			(start 0.508 -0.9398)
			(end 0.508 0.9398)
			(stroke
				(width 0.1524)
				(type default)
			)
			(layer "B.SilkS")
		)
		(fp_rect
			(start 0.508 0.9398)
			(end -0.508 -0.9398)
			(stroke
				(width 0)
				(type default)
			)
			(fill no)
			(layer "B.CrtYd")
		)
		(fp_rect
			(start 0.508 0.9398)
			(end -0.508 -0.9398)
			(stroke
				(width 0)
				(type default)
			)
			(fill no)
			(layer "B.Fab")
		)
		(pad "1" smd custom
			(at 0 -0.4445 90)
			(size 0.1397 0.1397)
			(layers "B.Cu" "B.Mask" "B.Paste")
			(net "P1V8_C")
			(options
				(clearance outline)
				(anchor circle)
			)
			(primitives
				(gr_poly
					(pts
						(arc
							(start -0.1778 0.2794)
							(mid -0.249642 0.249642)
							(end -0.2794 0.1778)
						)
						(arc
							(start -0.2794 -0.1778)
							(mid -0.249642 -0.249642)
							(end -0.1778 -0.2794)
						)
						(arc
							(start 0.1778 -0.2794)
							(mid 0.249642 -0.249642)
							(end 0.2794 -0.1778)
						)
						(arc
							(start 0.2794 0.1778)
							(mid 0.249642 0.249642)
							(end 0.1778 0.2794)
						)
					)
					(width 0)
					(fill yes)
				)
			)
		)
		(pad "2" smd custom
			(at 0 0.4445 90)
			(size 0.1397 0.1397)
			(layers "B.Cu" "B.Mask" "B.Paste")
			(net "IOC_SCL_2")
			(options
				(clearance outline)
				(anchor circle)
			)
			(primitives
				(gr_poly
					(pts
						(arc
							(start -0.1778 0.2794)
							(mid -0.249642 0.249642)
							(end -0.2794 0.1778)
						)
						(arc
							(start -0.2794 -0.1778)
							(mid -0.249642 -0.249642)
							(end -0.1778 -0.2794)
						)
						(arc
							(start 0.1778 -0.2794)
							(mid 0.249642 -0.249642)
							(end 0.2794 -0.1778)
						)
						(arc
							(start 0.2794 0.1778)
							(mid 0.249642 0.249642)
							(end 0.1778 0.2794)
						)
					)
					(width 0)
					(fill yes)
				)
			)
		)
	)
	(footprint ""
		(layer "B.Cu")
		(at 129.42697 -106.299 180)
		(property "Reference" "SR757"
			(at 0 0 0)
			(layer "B.SilkS")
			(hide yes)
			(effects
				(font
					(size 1.27 1.27)
				)
				(justify mirror)
			)
		)
		(property "Value" "3KR2J-2-GP"
			(at -0.064008 -3.993896 180)
			(unlocked yes)
			(layer "B.Fab")
			(hide yes)
			(effects
				(font
					(size 1.016 1.016)
					(thickness 0.1524)
				)
				(justify mirror)
			)
		)
		(property "Device Type" "R402H16"
			(at -0.064008 -5.517896 180)
			(unlocked yes)
			(layer "B.Fab")
			(hide yes)
			(effects
				(font
					(size 1.016 1.016)
					(thickness 0.1524)
				)
				(justify mirror)
			)
		)
		(duplicate_pad_numbers_are_jumpers no)
		(fp_line
			(start 0.508 -0.9398)
			(end 0.508 0.9398)
			(stroke
				(width 0.1524)
				(type default)
			)
			(layer "B.SilkS")
		)
		(fp_line
			(start -0.508 -0.9398)
			(end 0.508 -0.9398)
			(stroke
				(width 0.1524)
				(type default)
			)
			(layer "B.SilkS")
		)
		(fp_rect
			(start 0.508 0.9398)
			(end -0.508 -0.9398)
			(stroke
				(width 0)
				(type default)
			)
			(fill no)
			(layer "B.CrtYd")
		)
		(fp_rect
			(start 0.508 0.9398)
			(end -0.508 -0.9398)
			(stroke
				(width 0)
				(type default)
			)
			(fill no)
			(layer "B.Fab")
		)
		(pad "1" smd custom
			(at 0 -0.4445)
			(size 0.1397 0.1397)
			(layers "B.Cu" "B.Mask" "B.Paste")
			(net "EXP_RTRIM_A")
			(options
				(clearance outline)
				(anchor circle)
			)
			(primitives
				(gr_poly
					(pts
						(arc
							(start -0.1778 0.2794)
							(mid -0.249642 0.249642)
							(end -0.2794 0.1778)
						)
						(arc
							(start -0.2794 -0.1778)
							(mid -0.249642 -0.249642)
							(end -0.1778 -0.2794)
						)
						(arc
							(start 0.1778 -0.2794)
							(mid 0.249642 -0.249642)
							(end 0.2794 -0.1778)
						)
						(arc
							(start 0.2794 0.1778)
							(mid 0.249642 0.249642)
							(end 0.1778 0.2794)
						)
					)
					(width 0)
					(fill yes)
				)
			)
		)
		(pad "2" smd custom
			(at 0 0.4445)
			(size 0.1397 0.1397)
			(layers "B.Cu" "B.Mask" "B.Paste")
			(net "EXP_RTRIM_A_N")
			(options
				(clearance outline)
				(anchor circle)
			)
			(primitives
				(gr_poly
					(pts
						(arc
							(start -0.1778 0.2794)
							(mid -0.249642 0.249642)
							(end -0.2794 0.1778)
						)
						(arc
							(start -0.2794 -0.1778)
							(mid -0.249642 -0.249642)
							(end -0.1778 -0.2794)
						)
						(arc
							(start 0.1778 -0.2794)
							(mid 0.249642 -0.249642)
							(end 0.2794 -0.1778)
						)
						(arc
							(start 0.2794 0.1778)
							(mid 0.249642 0.249642)
							(end 0.1778 0.2794)
						)
					)
					(width 0)
					(fill yes)
				)
			)
		)
	)
	(footprint ""
		(layer "B.Cu")
		(at 100.97516 -31.640018)
		(property "Reference" "SC871"
			(at 0 0 0)
			(layer "B.SilkS")
			(hide yes)
			(effects
				(font
					(size 1.27 1.27)
				)
				(justify mirror)
			)
		)
		(property "Value" "SCD22U6D3V1MX-1-GP"
			(at 2.8321 -1.7399 0)
			(unlocked yes)
			(layer "B.Fab")
			(hide yes)
			(effects
				(font
					(size 1.016 1.016)
					(thickness 0.1524)
				)
				(justify mirror)
			)
		)
		(property "Device Type" "C0201H13"
			(at 2.8321 -3.2639 0)
			(unlocked yes)
			(layer "B.Fab")
			(hide yes)
			(effects
				(font
					(size 1.016 1.016)
					(thickness 0.1524)
				)
				(justify mirror)
			)
		)
		(duplicate_pad_numbers_are_jumpers no)
		(fp_rect
			(start 0.2794 0.6477)
			(end -0.2794 -0.6477)
			(stroke
				(width 0)
				(type default)
			)
			(fill no)
			(layer "B.CrtYd")
		)
		(fp_rect
			(start 0.2794 0.6477)
			(end -0.2794 -0.6477)
			(stroke
				(width 0)
				(type default)
			)
			(fill no)
			(layer "B.Fab")
		)
		(pad "1" smd custom
			(at 0 -0.2794 180)
			(size 0.0762 0.0762)
			(layers "B.Cu" "B.Mask" "B.Paste")
			(net "PCIE_SAS_C_CPU_RX_P5")
			(options
				(clearance outline)
				(anchor circle)
			)
			(primitives
				(gr_poly
					(pts
						(arc
							(start 0.1524 0.127)
							(mid 0.137521 0.162921)
							(end 0.1016 0.1778)
						)
						(arc
							(start -0.1016 0.1778)
							(mid -0.137521 0.162921)
							(end -0.1524 0.127)
						)
						(arc
							(start -0.1524 -0.127)
							(mid -0.137521 -0.162921)
							(end -0.1016 -0.1778)
						)
						(arc
							(start 0.1016 -0.1778)
							(mid 0.137521 -0.162921)
							(end 0.1524 -0.127)
						)
					)
					(width 0)
					(fill yes)
				)
			)
		)
		(pad "2" smd custom
			(at 0 0.2794 180)
			(size 0.0762 0.0762)
			(layers "B.Cu" "B.Mask" "B.Paste")
			(net "PCIE_SAS_CPU_RX_P5")
			(options
				(clearance outline)
				(anchor circle)
			)
			(primitives
				(gr_poly
					(pts
						(arc
							(start 0.1524 0.127)
							(mid 0.137521 0.162921)
							(end 0.1016 0.1778)
						)
						(arc
							(start -0.1016 0.1778)
							(mid -0.137521 0.162921)
							(end -0.1524 0.127)
						)
						(arc
							(start -0.1524 -0.127)
							(mid -0.137521 -0.162921)
							(end -0.1016 -0.1778)
						)
						(arc
							(start 0.1016 -0.1778)
							(mid 0.137521 -0.162921)
							(end 0.1524 -0.127)
						)
					)
					(width 0)
					(fill yes)
				)
			)
		)
	)
	(footprint ""
		(layer "B.Cu")
		(at 87.357966 -55.1815 180)
		(property "Reference" "SC1014"
			(at 0 0 0)
			(layer "B.SilkS")
			(hide yes)
			(effects
				(font
					(size 1.27 1.27)
				)
				(justify mirror)
			)
		)
		(property "Value" "SC1KP50V2KX-1GP"
			(at -1.1811 -2.7051 180)
			(unlocked yes)
			(layer "B.Fab")
			(hide yes)
			(effects
				(font
					(size 1.016 1.016)
					(thickness 0.1524)
				)
				(justify mirror)
			)
		)
		(property "Device Type" "C402H22"
			(at -1.1811 -4.2291 180)
			(unlocked yes)
			(layer "B.Fab")
			(hide yes)
			(effects
				(font
					(size 1.016 1.016)
					(thickness 0.1524)
				)
				(justify mirror)
			)
		)
		(duplicate_pad_numbers_are_jumpers no)
		(fp_rect
			(start 0.4318 0.9525)
			(end -0.4318 -0.9525)
			(stroke
				(width 0)
				(type default)
			)
			(fill no)
			(layer "B.CrtYd")
		)
		(fp_rect
			(start 0.4318 0.9525)
			(end -0.4318 -0.9525)
			(stroke
				(width 0)
				(type default)
			)
			(fill no)
			(layer "B.Fab")
		)
		(pad "1" smd custom
			(at 0 -0.4445)
			(size 0.1524 0.1524)
			(layers "B.Cu" "B.Mask" "B.Paste")
			(net "P1V8_C")
			(options
				(clearance outline)
				(anchor circle)
			)
			(primitives
				(gr_poly
					(pts
						(arc
							(start 0.3048 0.2032)
							(mid 0.275042 0.275042)
							(end 0.2032 0.3048)
						)
						(arc
							(start -0.2032 0.3048)
							(mid -0.275042 0.275042)
							(end -0.3048 0.2032)
						)
						(arc
							(start -0.3048 -0.2032)
							(mid -0.275042 -0.275042)
							(end -0.2032 -0.3048)
						)
						(arc
							(start 0.2032 -0.3048)
							(mid 0.275042 -0.275042)
							(end 0.3048 -0.2032)
						)
					)
					(width 0)
					(fill yes)
				)
			)
		)
		(pad "2" smd custom
			(at 0 0.4445)
			(size 0.1524 0.1524)
			(layers "B.Cu" "B.Mask" "B.Paste")
			(net "GND")
			(options
				(clearance outline)
				(anchor circle)
			)
			(primitives
				(gr_poly
					(pts
						(arc
							(start 0.3048 0.2032)
							(mid 0.275042 0.275042)
							(end 0.2032 0.3048)
						)
						(arc
							(start -0.2032 0.3048)
							(mid -0.275042 0.275042)
							(end -0.3048 0.2032)
						)
						(arc
							(start -0.3048 -0.2032)
							(mid -0.275042 -0.275042)
							(end -0.2032 -0.3048)
						)
						(arc
							(start 0.2032 -0.3048)
							(mid 0.275042 -0.275042)
							(end 0.3048 -0.2032)
						)
					)
					(width 0)
					(fill yes)
				)
			)
		)
	)
	(footprint ""
		(layer "B.Cu")
		(at 323.342 -184.404 180)
		(property "Reference" "C8081"
			(at 0 0 0)
			(layer "B.SilkS")
			(hide yes)
			(effects
				(font
					(size 1.27 1.27)
				)
				(justify mirror)
			)
		)
		(property "Value" "SCD1U25V2KX-2-GP"
			(at -1.1811 -2.7051 180)
			(unlocked yes)
			(layer "B.Fab")
			(hide yes)
			(effects
				(font
					(size 1.016 1.016)
					(thickness 0.1524)
				)
				(justify mirror)
			)
		)
		(property "Device Type" "C402H22"
			(at -1.1811 -4.2291 180)
			(unlocked yes)
			(layer "B.Fab")
			(hide yes)
			(effects
				(font
					(size 1.016 1.016)
					(thickness 0.1524)
				)
				(justify mirror)
			)
		)
		(duplicate_pad_numbers_are_jumpers no)
		(fp_rect
			(start 0.4318 0.9525)
			(end -0.4318 -0.9525)
			(stroke
				(width 0)
				(type default)
			)
			(fill no)
			(layer "B.CrtYd")
		)
		(fp_rect
			(start 0.4318 0.9525)
			(end -0.4318 -0.9525)
			(stroke
				(width 0)
				(type default)
			)
			(fill no)
			(layer "B.Fab")
		)
		(pad "1" smd custom
			(at 0 -0.4445)
			(size 0.1524 0.1524)
			(layers "B.Cu" "B.Mask" "B.Paste")
			(net "ADC_P0V9_E")
			(options
				(clearance outline)
				(anchor circle)
			)
			(primitives
				(gr_poly
					(pts
						(arc
							(start 0.3048 0.2032)
							(mid 0.275042 0.275042)
							(end 0.2032 0.3048)
						)
						(arc
							(start -0.2032 0.3048)
							(mid -0.275042 0.275042)
							(end -0.3048 0.2032)
						)
						(arc
							(start -0.3048 -0.2032)
							(mid -0.275042 -0.275042)
							(end -0.2032 -0.3048)
						)
						(arc
							(start 0.2032 -0.3048)
							(mid 0.275042 -0.275042)
							(end 0.3048 -0.2032)
						)
					)
					(width 0)
					(fill yes)
				)
			)
		)
		(pad "2" smd custom
			(at 0 0.4445)
			(size 0.1524 0.1524)
			(layers "B.Cu" "B.Mask" "B.Paste")
			(net "GND")
			(options
				(clearance outline)
				(anchor circle)
			)
			(primitives
				(gr_poly
					(pts
						(arc
							(start 0.3048 0.2032)
							(mid 0.275042 0.275042)
							(end 0.2032 0.3048)
						)
						(arc
							(start -0.2032 0.3048)
							(mid -0.275042 0.275042)
							(end -0.3048 0.2032)
						)
						(arc
							(start -0.3048 -0.2032)
							(mid -0.275042 -0.275042)
							(end -0.2032 -0.3048)
						)
						(arc
							(start 0.2032 -0.3048)
							(mid 0.275042 -0.275042)
							(end 0.3048 -0.2032)
						)
					)
					(width 0)
					(fill yes)
				)
			)
		)
	)
)
